FILE_TYPE = CONNECTIVITY;
{Allegro Design Entry HDL 16.6-p007 (v16-6-112F) 10/10/2012}
"PAGE_NUMBER" = 18;
0"NC";
END.
